# T6G (Grand Teton) — schematic netlist excerpt (pin names and nets, part order shuffled) for the footprints in the layout excerpt that follows; sources: Cadence DE-HDL packaged netlist, KiCad conversion of 04192023_DAF0TMB3IC0_F0TG_MB_C_brd_V02_OCP.brd

C827  Q_CAP_DIFFBUS  DIFF BUS_0.22UF 6.3V 20% X6S  pkg C0201  page 65 : \1\ = P5E_CPU1_P0_TX_C_DP<5> ; \2\ = P5E_CPU1_P0_TX_DP<5>

(kicad_pcb
	(version 20260206)
	(generator "pcbnew")
	(generator_version "10.0")
	(general
		(thickness 1.6)
		(legacy_teardrops no)
	)
	(paper "A4")
	(title_block
		(title "04192023_DAF0TMB3IC0_F0TG_MB_C_brd_V02_OCP.brd")
		(comment 1 "Grand Teton / footprints 4352-4352 of 8354")
	)
	(layers
		(0 "F.Cu" signal "TOP")
		(4 "In1.Cu" signal "GND")
		(6 "In2.Cu" signal "IN1")
		(8 "In3.Cu" signal "GND1")
		(10 "In4.Cu" signal "IN2")
		(12 "In5.Cu" signal "GND2")
		(14 "In6.Cu" signal "IN3")
		(16 "In7.Cu" signal "GND3")
		(18 "In8.Cu" signal "VCC")
		(20 "In9.Cu" signal "VCC1")
		(22 "In10.Cu" signal "GND4")
		(24 "In11.Cu" signal "IN4")
		(26 "In12.Cu" signal "GND5")
		(28 "In13.Cu" signal "IN5")
		(30 "In14.Cu" signal "GND6")
		(32 "In15.Cu" signal "IN6")
		(34 "In16.Cu" signal "GND7")
		(2 "B.Cu" signal "BOTTOM")
		(9 "F.Adhes" user "F.Adhesive")
		(11 "B.Adhes" user "B.Adhesive")
		(13 "F.Paste" user "Package Geometry/Pastemask Top")
		(15 "B.Paste" user "Package Geometry/Pastemask Bottom")
		(5 "F.SilkS" user "Ref Des/Silkscreen Top")
		(7 "B.SilkS" user "Ref Des/Silkscreen Bottom")
		(1 "F.Mask" user "Board Geometry/Soldermask Top")
		(3 "B.Mask" user "Board Geometry/Soldermask Bottom")
		(17 "Dwgs.User" user "User.Drawings")
		(19 "Cmts.User" user "User.Comments")
		(21 "Eco1.User" user "User.Eco1")
		(23 "Eco2.User" user "User.Eco2")
		(25 "Edge.Cuts" user "Board Geometry/Outline")
		(27 "Margin" user)
		(31 "F.CrtYd" user "Package Geometry/Place Bound Top")
		(29 "B.CrtYd" user "Package Geometry/Place Bound Bottom")
		(35 "F.Fab" user "Ref Des/Assembly Top")
		(33 "B.Fab" user "Ref Des/Assembly Bottom")
	)
	(footprint ""
		(layer "F.Cu")
		(at 49.796954 -373.03583 -90)
		(property "Reference" "C827"
			(at 0 0 270)
			(layer "F.SilkS")
			(hide yes)
			(effects
				(font
					(size 1.27 1.27)
				)
			)
		)
		(property "Value" ""
			(at 0 0 270)
			(layer "F.Fab")
			(effects
				(font
					(size 1.27 1.27)
				)
			)
		)
		(duplicate_pad_numbers_are_jumpers no)
		(fp_line
			(start -0.299974 0.150114)
			(end -0.299974 -0.150114)
			(stroke
				(width 0.1)
				(type default)
			)
			(layer "F.Fab")
		)
		(fp_line
			(start 0.299974 0.150114)
			(end -0.299974 0.150114)
			(stroke
				(width 0.1)
				(type default)
			)
			(layer "F.Fab")
		)
		(fp_line
			(start -0.299974 -0.150114)
			(end 0.299974 -0.150114)
			(stroke
				(width 0.1)
				(type default)
			)
			(layer "F.Fab")
		)
		(fp_line
			(start 0.299974 -0.150114)
			(end 0.299974 0.150114)
			(stroke
				(width 0.1)
				(type default)
			)
			(layer "F.Fab")
		)
		(pad "1" smd rect
			(at -0.2667 0 270)
			(size 0.3048 0.381)
			(layers "F.Cu" "F.Mask" "F.Paste")
			(net "P5E_CPU1_P0_TX_C_DP<5>")
		)
		(pad "2" smd rect
			(at 0.2667 0 270)
			(size 0.3048 0.381)
			(layers "F.Cu" "F.Mask" "F.Paste")
			(net "P5E_CPU1_P0_TX_DP<5>")
		)
	)
)
